(kicad_pcb
	(version 20260206)
	(generator "pcbnew")
	(generator_version "10.0")
	(general
		(thickness 1.6)
		(legacy_teardrops no)
	)
	(paper "A4")
	(title_block
		(title "01162023_DA0F0TEBIF0_F0T_Expander_BD_F_brd_V02_OCP.brd")
		(comment 1 "Grand Teton / footprints 3994-4000 of 9728")
	)
	(layers
		(0 "F.Cu" signal "TOP")
		(4 "In1.Cu" signal "GND")
		(6 "In2.Cu" signal "VCC")
		(8 "In3.Cu" signal "VCC1")
		(10 "In4.Cu" signal "GND1")
		(12 "In5.Cu" signal "IN1")
		(14 "In6.Cu" signal "GND2")
		(16 "In7.Cu" signal "IN2")
		(18 "In8.Cu" signal "GND3")
		(20 "In9.Cu" signal "IN3")
		(22 "In10.Cu" signal "GND4")
		(24 "In11.Cu" signal "IN4")
		(26 "In12.Cu" signal "GND5")
		(28 "In13.Cu" signal "IN5")
		(30 "In14.Cu" signal "GND6")
		(32 "In15.Cu" signal "IN6")
		(34 "In16.Cu" signal "GND7")
		(2 "B.Cu" signal "BOTTOM")
		(9 "F.Adhes" user "F.Adhesive")
		(11 "B.Adhes" user "B.Adhesive")
		(13 "F.Paste" user "Package Geometry/Pastemask Top")
		(15 "B.Paste" user "Package Geometry/Pastemask Bottom")
		(5 "F.SilkS" user "Ref Des/Silkscreen Top")
		(7 "B.SilkS" user "Ref Des/Silkscreen Bottom")
		(1 "F.Mask" user "Board Geometry/Soldermask Top")
		(3 "B.Mask" user "Board Geometry/Soldermask Bottom")
		(17 "Dwgs.User" user "User.Drawings")
		(19 "Cmts.User" user "User.Comments")
		(21 "Eco1.User" user "User.Eco1")
		(23 "Eco2.User" user "User.Eco2")
		(25 "Edge.Cuts" user "Board Geometry/Outline")
		(27 "Margin" user)
		(31 "F.CrtYd" user "Package Geometry/Place Bound Top")
		(29 "B.CrtYd" user "Package Geometry/Place Bound Bottom")
		(35 "F.Fab" user "Ref Des/Assembly Top")
		(33 "B.Fab" user "Ref Des/Assembly Bottom")
	)
	(footprint ""
		(layer "F.Cu")
		(at 198.76135 -135.28675 180)
		(property "Reference" "C229"
			(at 0 0 180)
			(layer "F.SilkS")
			(hide yes)
			(effects
				(font
					(size 1.27 1.27)
				)
			)
		)
		(property "Value" ""
			(at 0 0 180)
			(layer "F.Fab")
			(effects
				(font
					(size 1.27 1.27)
				)
			)
		)
		(duplicate_pad_numbers_are_jumpers no)
		(fp_line
			(start 0.299974 0.150114)
			(end -0.299974 0.150114)
			(stroke
				(width 0.1)
				(type default)
			)
			(layer "F.Fab")
		)
		(fp_line
			(start 0.299974 -0.150114)
			(end 0.299974 0.150114)
			(stroke
				(width 0.1)
				(type default)
			)
			(layer "F.Fab")
		)
		(fp_line
			(start -0.299974 0.150114)
			(end -0.299974 -0.150114)
			(stroke
				(width 0.1)
				(type default)
			)
			(layer "F.Fab")
		)
		(fp_line
			(start -0.299974 -0.150114)
			(end 0.299974 -0.150114)
			(stroke
				(width 0.1)
				(type default)
			)
			(layer "F.Fab")
		)
		(pad "1" smd rect
			(at -0.2667 0 180)
			(size 0.3048 0.381)
			(layers "F.Cu" "F.Mask" "F.Paste")
			(net "P5E_PEX1_STN0_TX_DN<7>")
		)
		(pad "2" smd rect
			(at 0.2667 0 180)
			(size 0.3048 0.381)
			(layers "F.Cu" "F.Mask" "F.Paste")
			(net "P5E_PEX1_STN0_TX_C_DN<7>")
		)
	)
	(footprint ""
		(layer "F.Cu")
		(at 357.367586 -262.17372 180)
		(property "Reference" "PR126"
			(at 0 0 180)
			(layer "F.SilkS")
			(hide yes)
			(effects
				(font
					(size 1.27 1.27)
				)
			)
		)
		(property "Value" ""
			(at 0 0 180)
			(layer "F.Fab")
			(effects
				(font
					(size 1.27 1.27)
				)
			)
		)
		(duplicate_pad_numbers_are_jumpers no)
		(fp_line
			(start 0.7874 0.4064)
			(end -0.7874 0.4064)
			(stroke
				(width 0.1524)
				(type default)
			)
			(layer "F.SilkS")
		)
		(fp_line
			(start 0.7874 -0.4064)
			(end 0.7874 0.4064)
			(stroke
				(width 0.1524)
				(type default)
			)
			(layer "F.SilkS")
		)
		(fp_line
			(start -0.7874 0.4064)
			(end -0.7874 -0.4064)
			(stroke
				(width 0.1524)
				(type default)
			)
			(layer "F.SilkS")
		)
		(fp_line
			(start -0.7874 -0.4064)
			(end 0.7874 -0.4064)
			(stroke
				(width 0.1524)
				(type default)
			)
			(layer "F.SilkS")
		)
		(fp_line
			(start 0.67945 0.3048)
			(end 0.120396 0.3048)
			(stroke
				(width 0.1)
				(type default)
			)
			(layer "F.Fab")
		)
		(fp_line
			(start 0.67945 -0.3048)
			(end 0.67945 0.3048)
			(stroke
				(width 0.1)
				(type default)
			)
			(layer "F.Fab")
		)
		(fp_line
			(start 0.12065 -0.2794)
			(end 0.12065 -0.3048)
			(stroke
				(width 0.1)
				(type default)
			)
			(layer "F.Fab")
		)
		(fp_line
			(start 0.12065 -0.3048)
			(end 0.67945 -0.3048)
			(stroke
				(width 0.1)
				(type default)
			)
			(layer "F.Fab")
		)
		(fp_line
			(start 0.120396 0.3048)
			(end 0.120396 0.2794)
			(stroke
				(width 0.1)
				(type default)
			)
			(layer "F.Fab")
		)
		(fp_line
			(start 0.120396 0.2794)
			(end -0.12065 0.2794)
			(stroke
				(width 0.1)
				(type default)
			)
			(layer "F.Fab")
		)
		(fp_line
			(start -0.12065 0.3048)
			(end -0.67945 0.3048)
			(stroke
				(width 0.1)
				(type default)
			)
			(layer "F.Fab")
		)
		(fp_line
			(start -0.12065 0.2794)
			(end -0.12065 0.3048)
			(stroke
				(width 0.1)
				(type default)
			)
			(layer "F.Fab")
		)
		(fp_line
			(start -0.12065 -0.2794)
			(end 0.12065 -0.2794)
			(stroke
				(width 0.1)
				(type default)
			)
			(layer "F.Fab")
		)
		(fp_line
			(start -0.12065 -0.305054)
			(end -0.12065 -0.2794)
			(stroke
				(width 0.1)
				(type default)
			)
			(layer "F.Fab")
		)
		(fp_line
			(start -0.67945 0.3048)
			(end -0.67945 -0.305054)
			(stroke
				(width 0.1)
				(type default)
			)
			(layer "F.Fab")
		)
		(fp_line
			(start -0.67945 -0.305054)
			(end -0.12065 -0.305054)
			(stroke
				(width 0.1)
				(type default)
			)
			(layer "F.Fab")
		)
		(pad "1" smd circle
			(at -0.40005 0 180)
			(size 0 0)
			(layers "F.Cu" "F.Mask" "F.Paste")
			(net "SH_P0V8_PEX2_VSEN2_R")
		)
		(pad "2" smd circle
			(at 0.40005 0 180)
			(size 0 0)
			(layers "F.Cu" "F.Mask" "F.Paste")
			(net "P0V8_PEX2_VSEN2")
		)
	)
	(footprint ""
		(layer "F.Cu")
		(at 52.243736 -49.95291 180)
		(property "Reference" "R522"
			(at 0 0 180)
			(layer "F.SilkS")
			(hide yes)
			(effects
				(font
					(size 1.27 1.27)
				)
			)
		)
		(property "Value" ""
			(at 0 0 180)
			(layer "F.Fab")
			(effects
				(font
					(size 1.27 1.27)
				)
			)
		)
		(duplicate_pad_numbers_are_jumpers no)
		(fp_line
			(start 0.7874 0.4064)
			(end -0.7874 0.4064)
			(stroke
				(width 0.1524)
				(type default)
			)
			(layer "F.SilkS")
		)
		(fp_line
			(start 0.7874 -0.4064)
			(end 0.7874 0.4064)
			(stroke
				(width 0.1524)
				(type default)
			)
			(layer "F.SilkS")
		)
		(fp_line
			(start -0.7874 0.4064)
			(end -0.7874 -0.4064)
			(stroke
				(width 0.1524)
				(type default)
			)
			(layer "F.SilkS")
		)
		(fp_line
			(start -0.7874 -0.4064)
			(end 0.7874 -0.4064)
			(stroke
				(width 0.1524)
				(type default)
			)
			(layer "F.SilkS")
		)
		(fp_line
			(start 0.67945 0.3048)
			(end 0.120396 0.3048)
			(stroke
				(width 0.1)
				(type default)
			)
			(layer "F.Fab")
		)
		(fp_line
			(start 0.67945 -0.3048)
			(end 0.67945 0.3048)
			(stroke
				(width 0.1)
				(type default)
			)
			(layer "F.Fab")
		)
		(fp_line
			(start 0.12065 -0.2794)
			(end 0.12065 -0.3048)
			(stroke
				(width 0.1)
				(type default)
			)
			(layer "F.Fab")
		)
		(fp_line
			(start 0.12065 -0.3048)
			(end 0.67945 -0.3048)
			(stroke
				(width 0.1)
				(type default)
			)
			(layer "F.Fab")
		)
		(fp_line
			(start 0.120396 0.3048)
			(end 0.120396 0.2794)
			(stroke
				(width 0.1)
				(type default)
			)
			(layer "F.Fab")
		)
		(fp_line
			(start 0.120396 0.2794)
			(end -0.12065 0.2794)
			(stroke
				(width 0.1)
				(type default)
			)
			(layer "F.Fab")
		)
		(fp_line
			(start -0.12065 0.3048)
			(end -0.67945 0.3048)
			(stroke
				(width 0.1)
				(type default)
			)
			(layer "F.Fab")
		)
		(fp_line
			(start -0.12065 0.2794)
			(end -0.12065 0.3048)
			(stroke
				(width 0.1)
				(type default)
			)
			(layer "F.Fab")
		)
		(fp_line
			(start -0.12065 -0.2794)
			(end 0.12065 -0.2794)
			(stroke
				(width 0.1)
				(type default)
			)
			(layer "F.Fab")
		)
		(fp_line
			(start -0.12065 -0.305054)
			(end -0.12065 -0.2794)
			(stroke
				(width 0.1)
				(type default)
			)
			(layer "F.Fab")
		)
		(fp_line
			(start -0.67945 0.3048)
			(end -0.67945 -0.305054)
			(stroke
				(width 0.1)
				(type default)
			)
			(layer "F.Fab")
		)
		(fp_line
			(start -0.67945 -0.305054)
			(end -0.12065 -0.305054)
			(stroke
				(width 0.1)
				(type default)
			)
			(layer "F.Fab")
		)
		(pad "1" smd circle
			(at -0.40005 0 180)
			(size 0 0)
			(layers "F.Cu" "F.Mask" "F.Paste")
			(net "SMB_BIC_I2C6_MUX_SSD_0_7_ADC_R_SCL")
		)
		(pad "2" smd circle
			(at 0.40005 0 180)
			(size 0 0)
			(layers "F.Cu" "F.Mask" "F.Paste")
			(net "SMB_SSD1_ADC_SCL")
		)
	)
	(footprint ""
		(layer "F.Cu")
		(at 95.9104 -190.5)
		(property "Reference" "R6627"
			(at 0 0 0)
			(layer "F.SilkS")
			(hide yes)
			(effects
				(font
					(size 1.27 1.27)
				)
			)
		)
		(property "Value" ""
			(at 0 0 0)
			(layer "F.Fab")
			(effects
				(font
					(size 1.27 1.27)
				)
			)
		)
		(duplicate_pad_numbers_are_jumpers no)
		(fp_line
			(start -0.7874 -0.4064)
			(end 0.7874 -0.4064)
			(stroke
				(width 0.1524)
				(type default)
			)
			(layer "F.SilkS")
		)
		(fp_line
			(start -0.7874 0.4064)
			(end -0.7874 -0.4064)
			(stroke
				(width 0.1524)
				(type default)
			)
			(layer "F.SilkS")
		)
		(fp_line
			(start 0.7874 -0.4064)
			(end 0.7874 0.4064)
			(stroke
				(width 0.1524)
				(type default)
			)
			(layer "F.SilkS")
		)
		(fp_line
			(start 0.7874 0.4064)
			(end -0.7874 0.4064)
			(stroke
				(width 0.1524)
				(type default)
			)
			(layer "F.SilkS")
		)
		(fp_line
			(start -0.67945 -0.305054)
			(end -0.12065 -0.305054)
			(stroke
				(width 0.1)
				(type default)
			)
			(layer "F.Fab")
		)
		(fp_line
			(start -0.67945 0.3048)
			(end -0.67945 -0.305054)
			(stroke
				(width 0.1)
				(type default)
			)
			(layer "F.Fab")
		)
		(fp_line
			(start -0.12065 -0.305054)
			(end -0.12065 -0.2794)
			(stroke
				(width 0.1)
				(type default)
			)
			(layer "F.Fab")
		)
		(fp_line
			(start -0.12065 -0.2794)
			(end 0.12065 -0.2794)
			(stroke
				(width 0.1)
				(type default)
			)
			(layer "F.Fab")
		)
		(fp_line
			(start -0.12065 0.2794)
			(end -0.12065 0.3048)
			(stroke
				(width 0.1)
				(type default)
			)
			(layer "F.Fab")
		)
		(fp_line
			(start -0.12065 0.3048)
			(end -0.67945 0.3048)
			(stroke
				(width 0.1)
				(type default)
			)
			(layer "F.Fab")
		)
		(fp_line
			(start 0.120396 0.2794)
			(end -0.12065 0.2794)
			(stroke
				(width 0.1)
				(type default)
			)
			(layer "F.Fab")
		)
		(fp_line
			(start 0.120396 0.3048)
			(end 0.120396 0.2794)
			(stroke
				(width 0.1)
				(type default)
			)
			(layer "F.Fab")
		)
		(fp_line
			(start 0.12065 -0.3048)
			(end 0.67945 -0.3048)
			(stroke
				(width 0.1)
				(type default)
			)
			(layer "F.Fab")
		)
		(fp_line
			(start 0.12065 -0.2794)
			(end 0.12065 -0.3048)
			(stroke
				(width 0.1)
				(type default)
			)
			(layer "F.Fab")
		)
		(fp_line
			(start 0.67945 -0.3048)
			(end 0.67945 0.3048)
			(stroke
				(width 0.1)
				(type default)
			)
			(layer "F.Fab")
		)
		(fp_line
			(start 0.67945 0.3048)
			(end 0.120396 0.3048)
			(stroke
				(width 0.1)
				(type default)
			)
			(layer "F.Fab")
		)
		(pad "1" smd circle
			(at -0.40005 0)
			(size 0 0)
			(layers "F.Cu" "F.Mask" "F.Paste")
			(net "UART_PEX2_CLI_BUF_R_TX")
		)
		(pad "2" smd circle
			(at 0.40005 0)
			(size 0 0)
			(layers "F.Cu" "F.Mask" "F.Paste")
			(net "UART_PEX2_CLI_CP2108_TX")
		)
	)
	(footprint ""
		(layer "F.Cu")
		(at 196.119242 -133.480302 180)
		(property "Reference" "C231"
			(at 0 0 180)
			(layer "F.SilkS")
			(hide yes)
			(effects
				(font
					(size 1.27 1.27)
				)
			)
		)
		(property "Value" ""
			(at 0 0 180)
			(layer "F.Fab")
			(effects
				(font
					(size 1.27 1.27)
				)
			)
		)
		(duplicate_pad_numbers_are_jumpers no)
		(fp_line
			(start 0.299974 0.150114)
			(end -0.299974 0.150114)
			(stroke
				(width 0.1)
				(type default)
			)
			(layer "F.Fab")
		)
		(fp_line
			(start 0.299974 -0.150114)
			(end 0.299974 0.150114)
			(stroke
				(width 0.1)
				(type default)
			)
			(layer "F.Fab")
		)
		(fp_line
			(start -0.299974 0.150114)
			(end -0.299974 -0.150114)
			(stroke
				(width 0.1)
				(type default)
			)
			(layer "F.Fab")
		)
		(fp_line
			(start -0.299974 -0.150114)
			(end 0.299974 -0.150114)
			(stroke
				(width 0.1)
				(type default)
			)
			(layer "F.Fab")
		)
		(pad "1" smd rect
			(at -0.2667 0 180)
			(size 0.3048 0.381)
			(layers "F.Cu" "F.Mask" "F.Paste")
			(net "P5E_PEX1_STN0_TX_DN<6>")
		)
		(pad "2" smd rect
			(at 0.2667 0 180)
			(size 0.3048 0.381)
			(layers "F.Cu" "F.Mask" "F.Paste")
			(net "P5E_PEX1_STN0_TX_C_DN<6>")
		)
	)
	(footprint ""
		(layer "F.Cu")
		(at 316.3189 -59.574684 90)
		(property "Reference" "PC577"
			(at 0 0 90)
			(layer "F.SilkS")
			(hide yes)
			(effects
				(font
					(size 1.27 1.27)
				)
			)
		)
		(property "Value" ""
			(at 0 0 90)
			(layer "F.Fab")
			(effects
				(font
					(size 1.27 1.27)
				)
			)
		)
		(duplicate_pad_numbers_are_jumpers no)
		(fp_line
			(start 0.7874 -0.4064)
			(end 0.7874 0.4064)
			(stroke
				(width 0.1524)
				(type default)
			)
			(layer "F.SilkS")
		)
		(fp_line
			(start -0.7874 -0.4064)
			(end 0.7874 -0.4064)
			(stroke
				(width 0.1524)
				(type default)
			)
			(layer "F.SilkS")
		)
		(fp_line
			(start 0.7874 0.4064)
			(end -0.7874 0.4064)
			(stroke
				(width 0.1524)
				(type default)
			)
			(layer "F.SilkS")
		)
		(fp_line
			(start -0.7874 0.4064)
			(end -0.7874 -0.4064)
			(stroke
				(width 0.1524)
				(type default)
			)
			(layer "F.SilkS")
		)
		(fp_line
			(start -0.12065 -0.305054)
			(end -0.12065 -0.2794)
			(stroke
				(width 0.1)
				(type default)
			)
			(layer "F.Fab")
		)
		(fp_line
			(start -0.67945 -0.305054)
			(end -0.12065 -0.305054)
			(stroke
				(width 0.1)
				(type default)
			)
			(layer "F.Fab")
		)
		(fp_line
			(start 0.67945 -0.3048)
			(end 0.67945 0.3048)
			(stroke
				(width 0.1)
				(type default)
			)
			(layer "F.Fab")
		)
		(fp_line
			(start 0.12065 -0.3048)
			(end 0.67945 -0.3048)
			(stroke
				(width 0.1)
				(type default)
			)
			(layer "F.Fab")
		)
		(fp_line
			(start 0.12065 -0.2794)
			(end 0.12065 -0.3048)
			(stroke
				(width 0.1)
				(type default)
			)
			(layer "F.Fab")
		)
		(fp_line
			(start -0.12065 -0.2794)
			(end 0.12065 -0.2794)
			(stroke
				(width 0.1)
				(type default)
			)
			(layer "F.Fab")
		)
		(fp_line
			(start 0.120396 0.2794)
			(end -0.12065 0.2794)
			(stroke
				(width 0.1)
				(type default)
			)
			(layer "F.Fab")
		)
		(fp_line
			(start -0.12065 0.2794)
			(end -0.12065 0.3048)
			(stroke
				(width 0.1)
				(type default)
			)
			(layer "F.Fab")
		)
		(fp_line
			(start 0.67945 0.3048)
			(end 0.120396 0.3048)
			(stroke
				(width 0.1)
				(type default)
			)
			(layer "F.Fab")
		)
		(fp_line
			(start 0.120396 0.3048)
			(end 0.120396 0.2794)
			(stroke
				(width 0.1)
				(type default)
			)
			(layer "F.Fab")
		)
		(fp_line
			(start -0.12065 0.3048)
			(end -0.67945 0.3048)
			(stroke
				(width 0.1)
				(type default)
			)
			(layer "F.Fab")
		)
		(fp_line
			(start -0.67945 0.3048)
			(end -0.67945 -0.305054)
			(stroke
				(width 0.1)
				(type default)
			)
			(layer "F.Fab")
		)
		(pad "1" smd circle
			(at -0.40005 0 90)
			(size 0 0)
			(layers "F.Cu" "F.Mask" "F.Paste")
			(net "P5V_AUX")
		)
		(pad "2" smd circle
			(at 0.40005 0 90)
			(size 0 0)
			(layers "F.Cu" "F.Mask" "F.Paste")
			(net "GND")
		)
	)
	(footprint ""
		(layer "F.Cu")
		(at 249.733562 -211.622386)
		(property "Reference" "R4432"
			(at 0 0 0)
			(layer "F.SilkS")
			(hide yes)
			(effects
				(font
					(size 1.27 1.27)
				)
			)
		)
		(property "Value" ""
			(at 0 0 0)
			(layer "F.Fab")
			(effects
				(font
					(size 1.27 1.27)
				)
			)
		)
		(duplicate_pad_numbers_are_jumpers no)
		(fp_line
			(start -0.7874 -0.4064)
			(end 0.7874 -0.4064)
			(stroke
				(width 0.1524)
				(type default)
			)
			(layer "F.SilkS")
		)
		(fp_line
			(start -0.7874 0.4064)
			(end -0.7874 -0.4064)
			(stroke
				(width 0.1524)
				(type default)
			)
			(layer "F.SilkS")
		)
		(fp_line
			(start 0.7874 -0.4064)
			(end 0.7874 0.4064)
			(stroke
				(width 0.1524)
				(type default)
			)
			(layer "F.SilkS")
		)
		(fp_line
			(start 0.7874 0.4064)
			(end -0.7874 0.4064)
			(stroke
				(width 0.1524)
				(type default)
			)
			(layer "F.SilkS")
		)
		(fp_line
			(start -0.67945 -0.305054)
			(end -0.12065 -0.305054)
			(stroke
				(width 0.1)
				(type default)
			)
			(layer "F.Fab")
		)
		(fp_line
			(start -0.67945 0.3048)
			(end -0.67945 -0.305054)
			(stroke
				(width 0.1)
				(type default)
			)
			(layer "F.Fab")
		)
		(fp_line
			(start -0.12065 -0.305054)
			(end -0.12065 -0.2794)
			(stroke
				(width 0.1)
				(type default)
			)
			(layer "F.Fab")
		)
		(fp_line
			(start -0.12065 -0.2794)
			(end 0.12065 -0.2794)
			(stroke
				(width 0.1)
				(type default)
			)
			(layer "F.Fab")
		)
		(fp_line
			(start -0.12065 0.2794)
			(end -0.12065 0.3048)
			(stroke
				(width 0.1)
				(type default)
			)
			(layer "F.Fab")
		)
		(fp_line
			(start -0.12065 0.3048)
			(end -0.67945 0.3048)
			(stroke
				(width 0.1)
				(type default)
			)
			(layer "F.Fab")
		)
		(fp_line
			(start 0.120396 0.2794)
			(end -0.12065 0.2794)
			(stroke
				(width 0.1)
				(type default)
			)
			(layer "F.Fab")
		)
		(fp_line
			(start 0.120396 0.3048)
			(end 0.120396 0.2794)
			(stroke
				(width 0.1)
				(type default)
			)
			(layer "F.Fab")
		)
		(fp_line
			(start 0.12065 -0.3048)
			(end 0.67945 -0.3048)
			(stroke
				(width 0.1)
				(type default)
			)
			(layer "F.Fab")
		)
		(fp_line
			(start 0.12065 -0.2794)
			(end 0.12065 -0.3048)
			(stroke
				(width 0.1)
				(type default)
			)
			(layer "F.Fab")
		)
		(fp_line
			(start 0.67945 -0.3048)
			(end 0.67945 0.3048)
			(stroke
				(width 0.1)
				(type default)
			)
			(layer "F.Fab")
		)
		(fp_line
			(start 0.67945 0.3048)
			(end 0.120396 0.3048)
			(stroke
				(width 0.1)
				(type default)
			)
			(layer "F.Fab")
		)
		(pad "1" smd circle
			(at -0.40005 0)
			(size 0 0)
			(layers "F.Cu" "F.Mask" "F.Paste")
			(net "P1V2_AUX")
		)
		(pad "2" smd circle
			(at 0.40005 0)
			(size 0 0)
			(layers "F.Cu" "F.Mask" "F.Paste")
			(net "P1V2_AUX_ADJ")
		)
	)
)
